# SCM (Grand Teton) — schematic netlist excerpt (pin names and nets, part order shuffled) for the footprints in the layout excerpt that follows; sources: Cadence DE-HDL packaged netlist, KiCad conversion of 12092022_DA0F0TMDCD0_F0T_Management_Board_D_brd_V3_OCP.brd

R234  Q_RES  49.9K 1% CHIP  pkg 0402LF  page 16 : A = GND ; B = A_BMC_ADCREXT1
R290  Q_RES  47K 1% CHIP  pkg 0402LF  page 22 : A = BJT_Q3_B ; B = RST_BMC_EXTRST_R1_N

(kicad_pcb
	(version 20260206)
	(generator "pcbnew")
	(generator_version "10.0")
	(general
		(thickness 1.6)
		(legacy_teardrops no)
	)
	(paper "A4")
	(title_block
		(title "12092022_DA0F0TMDCD0_F0T_Management_Board_D_brd_V3_OCP.brd")
		(comment 1 "Grand Teton / footprints 605-607 of 1440")
	)
	(layers
		(0 "F.Cu" signal "TOP")
		(4 "In1.Cu" signal "GND")
		(6 "In2.Cu" signal "IN1")
		(8 "In3.Cu" signal "GND1")
		(10 "In4.Cu" signal "IN2")
		(12 "In5.Cu" signal "VCC")
		(14 "In6.Cu" signal "VCC1")
		(16 "In7.Cu" signal "IN3")
		(18 "In8.Cu" signal "GND2")
		(20 "In9.Cu" signal "IN4")
		(22 "In10.Cu" signal "GND3")
		(2 "B.Cu" signal "BOTTOM")
		(9 "F.Adhes" user "F.Adhesive")
		(11 "B.Adhes" user "B.Adhesive")
		(13 "F.Paste" user "Package Geometry/Pastemask Top")
		(15 "B.Paste" user "Package Geometry/Pastemask Bottom")
		(5 "F.SilkS" user "Ref Des/Silkscreen Top")
		(7 "B.SilkS" user "Ref Des/Silkscreen Bottom")
		(1 "F.Mask" user "Board Geometry/Soldermask Top")
		(3 "B.Mask" user "Board Geometry/Soldermask Bottom")
		(17 "Dwgs.User" user "User.Drawings")
		(19 "Cmts.User" user "User.Comments")
		(21 "Eco1.User" user "User.Eco1")
		(23 "Eco2.User" user "User.Eco2")
		(25 "Edge.Cuts" user "Board Geometry/Outline")
		(27 "Margin" user)
		(31 "F.CrtYd" user "Package Geometry/Place Bound Top")
		(29 "B.CrtYd" user "Package Geometry/Place Bound Bottom")
		(35 "F.Fab" user "Ref Des/Assembly Top")
		(33 "B.Fab" user "Ref Des/Assembly Bottom")
	)
	(footprint ""
		(layer "F.Cu")
		(at 49.67478 -66.25082)
		(property "Reference" "R234"
			(at 0 0 0)
			(layer "F.SilkS")
			(hide yes)
			(effects
				(font
					(size 1.27 1.27)
				)
			)
		)
		(property "Value" ""
			(at 0 0 0)
			(layer "F.Fab")
			(effects
				(font
					(size 1.27 1.27)
				)
			)
		)
		(duplicate_pad_numbers_are_jumpers no)
		(fp_line
			(start -0.7874 -0.4064)
			(end 0.7874 -0.4064)
			(stroke
				(width 0.1524)
				(type default)
			)
			(layer "F.SilkS")
		)
		(fp_line
			(start -0.7874 0.4064)
			(end -0.7874 -0.4064)
			(stroke
				(width 0.1524)
				(type default)
			)
			(layer "F.SilkS")
		)
		(fp_line
			(start 0.7874 -0.4064)
			(end 0.7874 0.4064)
			(stroke
				(width 0.1524)
				(type default)
			)
			(layer "F.SilkS")
		)
		(fp_line
			(start 0.7874 0.4064)
			(end -0.7874 0.4064)
			(stroke
				(width 0.1524)
				(type default)
			)
			(layer "F.SilkS")
		)
		(fp_line
			(start -0.67945 -0.305054)
			(end -0.12065 -0.305054)
			(stroke
				(width 0.1)
				(type default)
			)
			(layer "F.Fab")
		)
		(fp_line
			(start -0.67945 0.3048)
			(end -0.67945 -0.305054)
			(stroke
				(width 0.1)
				(type default)
			)
			(layer "F.Fab")
		)
		(fp_line
			(start -0.12065 -0.305054)
			(end -0.12065 -0.2794)
			(stroke
				(width 0.1)
				(type default)
			)
			(layer "F.Fab")
		)
		(fp_line
			(start -0.12065 -0.2794)
			(end 0.12065 -0.2794)
			(stroke
				(width 0.1)
				(type default)
			)
			(layer "F.Fab")
		)
		(fp_line
			(start -0.12065 0.2794)
			(end -0.12065 0.3048)
			(stroke
				(width 0.1)
				(type default)
			)
			(layer "F.Fab")
		)
		(fp_line
			(start -0.12065 0.3048)
			(end -0.67945 0.3048)
			(stroke
				(width 0.1)
				(type default)
			)
			(layer "F.Fab")
		)
		(fp_line
			(start 0.120396 0.2794)
			(end -0.12065 0.2794)
			(stroke
				(width 0.1)
				(type default)
			)
			(layer "F.Fab")
		)
		(fp_line
			(start 0.120396 0.3048)
			(end 0.120396 0.2794)
			(stroke
				(width 0.1)
				(type default)
			)
			(layer "F.Fab")
		)
		(fp_line
			(start 0.12065 -0.3048)
			(end 0.67945 -0.3048)
			(stroke
				(width 0.1)
				(type default)
			)
			(layer "F.Fab")
		)
		(fp_line
			(start 0.12065 -0.2794)
			(end 0.12065 -0.3048)
			(stroke
				(width 0.1)
				(type default)
			)
			(layer "F.Fab")
		)
		(fp_line
			(start 0.67945 -0.3048)
			(end 0.67945 0.3048)
			(stroke
				(width 0.1)
				(type default)
			)
			(layer "F.Fab")
		)
		(fp_line
			(start 0.67945 0.3048)
			(end 0.120396 0.3048)
			(stroke
				(width 0.1)
				(type default)
			)
			(layer "F.Fab")
		)
		(pad "1" smd circle
			(at -0.40005 0)
			(size 0 0)
			(layers "F.Cu" "F.Mask" "F.Paste")
			(net "GND")
		)
		(pad "2" smd circle
			(at 0.40005 0)
			(size 0 0)
			(layers "F.Cu" "F.Mask" "F.Paste")
			(net "A_BMC_ADCREXT1")
		)
	)
	(footprint ""
		(layer "F.Cu")
		(at 82.0928 -114.681)
		(property "Reference" ""
			(at 0 0 0)
			(layer "F.SilkS")
			(hide yes)
			(effects
				(font
					(size 1.27 1.27)
				)
			)
		)
		(property "Value" ""
			(at 0 0 0)
			(layer "F.Fab")
			(effects
				(font
					(size 1.27 1.27)
				)
			)
		)
		(duplicate_pad_numbers_are_jumpers no)
		(pad "1" smd circle
			(at 0 0)
			(size 0.9906 0.9906)
			(layers "F.Cu" "F.Mask" "F.Paste")
			(net "Net_597")
		)
	)
	(footprint ""
		(layer "F.Cu")
		(at 49.2125 -92.0115 90)
		(property "Reference" "R290"
			(at 0 0 90)
			(layer "F.SilkS")
			(hide yes)
			(effects
				(font
					(size 1.27 1.27)
				)
			)
		)
		(property "Value" ""
			(at 0 0 90)
			(layer "F.Fab")
			(effects
				(font
					(size 1.27 1.27)
				)
			)
		)
		(duplicate_pad_numbers_are_jumpers no)
		(fp_line
			(start 0.7874 -0.4064)
			(end 0.7874 0.4064)
			(stroke
				(width 0.1524)
				(type default)
			)
			(layer "F.SilkS")
		)
		(fp_line
			(start -0.7874 -0.4064)
			(end 0.7874 -0.4064)
			(stroke
				(width 0.1524)
				(type default)
			)
			(layer "F.SilkS")
		)
		(fp_line
			(start 0.7874 0.4064)
			(end -0.7874 0.4064)
			(stroke
				(width 0.1524)
				(type default)
			)
			(layer "F.SilkS")
		)
		(fp_line
			(start -0.7874 0.4064)
			(end -0.7874 -0.4064)
			(stroke
				(width 0.1524)
				(type default)
			)
			(layer "F.SilkS")
		)
		(fp_line
			(start -0.12065 -0.305054)
			(end -0.12065 -0.2794)
			(stroke
				(width 0.1)
				(type default)
			)
			(layer "F.Fab")
		)
		(fp_line
			(start -0.67945 -0.305054)
			(end -0.12065 -0.305054)
			(stroke
				(width 0.1)
				(type default)
			)
			(layer "F.Fab")
		)
		(fp_line
			(start 0.67945 -0.3048)
			(end 0.67945 0.3048)
			(stroke
				(width 0.1)
				(type default)
			)
			(layer "F.Fab")
		)
		(fp_line
			(start 0.12065 -0.3048)
			(end 0.67945 -0.3048)
			(stroke
				(width 0.1)
				(type default)
			)
			(layer "F.Fab")
		)
		(fp_line
			(start 0.12065 -0.2794)
			(end 0.12065 -0.3048)
			(stroke
				(width 0.1)
				(type default)
			)
			(layer "F.Fab")
		)
		(fp_line
			(start -0.12065 -0.2794)
			(end 0.12065 -0.2794)
			(stroke
				(width 0.1)
				(type default)
			)
			(layer "F.Fab")
		)
		(fp_line
			(start 0.120396 0.2794)
			(end -0.12065 0.2794)
			(stroke
				(width 0.1)
				(type default)
			)
			(layer "F.Fab")
		)
		(fp_line
			(start -0.12065 0.2794)
			(end -0.12065 0.3048)
			(stroke
				(width 0.1)
				(type default)
			)
			(layer "F.Fab")
		)
		(fp_line
			(start 0.67945 0.3048)
			(end 0.120396 0.3048)
			(stroke
				(width 0.1)
				(type default)
			)
			(layer "F.Fab")
		)
		(fp_line
			(start 0.120396 0.3048)
			(end 0.120396 0.2794)
			(stroke
				(width 0.1)
				(type default)
			)
			(layer "F.Fab")
		)
		(fp_line
			(start -0.12065 0.3048)
			(end -0.67945 0.3048)
			(stroke
				(width 0.1)
				(type default)
			)
			(layer "F.Fab")
		)
		(fp_line
			(start -0.67945 0.3048)
			(end -0.67945 -0.305054)
			(stroke
				(width 0.1)
				(type default)
			)
			(layer "F.Fab")
		)
		(pad "1" smd circle
			(at -0.40005 0 90)
			(size 0 0)
			(layers "F.Cu" "F.Mask" "F.Paste")
			(net "BJT_Q3_B")
		)
		(pad "2" smd circle
			(at 0.40005 0 90)
			(size 0 0)
			(layers "F.Cu" "F.Mask" "F.Paste")
			(net "RST_BMC_EXTRST_R1_N")
		)
	)
)
